# T6G (Grand Teton) — schematic netlist excerpt (pin names and nets, part order shuffled) for the footprints in the layout excerpt that follows; sources: Cadence DE-HDL packaged netlist, KiCad conversion of 04192023_DAF0TMB3IC0_F0TG_MB_C_brd_V02_OCP.brd

C2256  Q_CAP  22UF 4V 20% X6S  pkg C0402  page 69 : A = PVDDCR_CPU1_P0 ; B = GND
R2803  Q_RES  0 5% CHIP  pkg 0402LF  page 240 : A = FM_FAN_PWR_EN_R ; B = FM_FAN_PWR_EN
TP10  TP  NA  pkg TP  page 27 : TP = VSENSE_PVDDCR_SOC_P0_DP

(kicad_pcb
	(version 20260206)
	(generator "pcbnew")
	(generator_version "10.0")
	(general
		(thickness 1.6)
		(legacy_teardrops no)
	)
	(paper "A4")
	(title_block
		(title "04192023_DAF0TMB3IC0_F0TG_MB_C_brd_V02_OCP.brd")
		(comment 1 "Grand Teton / footprints 7895-7897 of 8354")
	)
	(layers
		(0 "F.Cu" signal "TOP")
		(4 "In1.Cu" signal "GND")
		(6 "In2.Cu" signal "IN1")
		(8 "In3.Cu" signal "GND1")
		(10 "In4.Cu" signal "IN2")
		(12 "In5.Cu" signal "GND2")
		(14 "In6.Cu" signal "IN3")
		(16 "In7.Cu" signal "GND3")
		(18 "In8.Cu" signal "VCC")
		(20 "In9.Cu" signal "VCC1")
		(22 "In10.Cu" signal "GND4")
		(24 "In11.Cu" signal "IN4")
		(26 "In12.Cu" signal "GND5")
		(28 "In13.Cu" signal "IN5")
		(30 "In14.Cu" signal "GND6")
		(32 "In15.Cu" signal "IN6")
		(34 "In16.Cu" signal "GND7")
		(2 "B.Cu" signal "BOTTOM")
		(9 "F.Adhes" user "F.Adhesive")
		(11 "B.Adhes" user "B.Adhesive")
		(13 "F.Paste" user "Package Geometry/Pastemask Top")
		(15 "B.Paste" user "Package Geometry/Pastemask Bottom")
		(5 "F.SilkS" user "Ref Des/Silkscreen Top")
		(7 "B.SilkS" user "Ref Des/Silkscreen Bottom")
		(1 "F.Mask" user "Board Geometry/Soldermask Top")
		(3 "B.Mask" user "Board Geometry/Soldermask Bottom")
		(17 "Dwgs.User" user "User.Drawings")
		(19 "Cmts.User" user "User.Comments")
		(21 "Eco1.User" user "User.Eco1")
		(23 "Eco2.User" user "User.Eco2")
		(25 "Edge.Cuts" user "Board Geometry/Outline")
		(27 "Margin" user)
		(31 "F.CrtYd" user "Package Geometry/Place Bound Top")
		(29 "B.CrtYd" user "Package Geometry/Place Bound Bottom")
		(35 "F.Fab" user "Ref Des/Assembly Top")
		(33 "B.Fab" user "Ref Des/Assembly Bottom")
	)
	(footprint ""
		(layer "B.Cu")
		(at 421.895778 -177.861722)
		(property "Reference" "TP10"
			(at -0.61468 0.184912 0)
			(unlocked yes)
			(layer "B.SilkS")
			(effects
				(font
					(size 0.7874 0.5842)
					(thickness 0.1524)
				)
				(justify left mirror)
			)
		)
		(property "Value" ""
			(at 0 0 0)
			(layer "B.Fab")
			(effects
				(font
					(size 1.27 1.27)
				)
				(justify mirror)
			)
		)
		(duplicate_pad_numbers_are_jumpers no)
		(pad "1" smd circle
			(at 0 0 180)
			(size 0.6604 0.6604)
			(layers "B.Cu" "B.Mask" "B.Paste")
			(net "VSENSE_PVDDCR_SOC_P0_DP")
		)
	)
	(footprint ""
		(layer "B.Cu")
		(at 241.756692 -422.849548 90)
		(property "Reference" "R2803"
			(at 0 0 90)
			(layer "B.SilkS")
			(hide yes)
			(effects
				(font
					(size 1.27 1.27)
				)
				(justify mirror)
			)
		)
		(property "Value" ""
			(at 0 0 90)
			(layer "B.Fab")
			(effects
				(font
					(size 1.27 1.27)
				)
				(justify mirror)
			)
		)
		(duplicate_pad_numbers_are_jumpers no)
		(fp_line
			(start 0.7874 -0.4064)
			(end -0.7874 -0.4064)
			(stroke
				(width 0.1524)
				(type default)
			)
			(layer "B.SilkS")
		)
		(fp_line
			(start -0.7874 -0.4064)
			(end -0.7874 0.4064)
			(stroke
				(width 0.1524)
				(type default)
			)
			(layer "B.SilkS")
		)
		(fp_line
			(start 0.7874 0.4064)
			(end 0.7874 -0.4064)
			(stroke
				(width 0.1524)
				(type default)
			)
			(layer "B.SilkS")
		)
		(fp_line
			(start -0.7874 0.4064)
			(end 0.7874 0.4064)
			(stroke
				(width 0.1524)
				(type default)
			)
			(layer "B.SilkS")
		)
		(fp_line
			(start 0.67945 -0.305054)
			(end 0.12065 -0.305054)
			(stroke
				(width 0.1)
				(type default)
			)
			(layer "B.Fab")
		)
		(fp_line
			(start 0.12065 -0.305054)
			(end 0.12065 -0.2794)
			(stroke
				(width 0.1)
				(type default)
			)
			(layer "B.Fab")
		)
		(fp_line
			(start -0.12065 -0.3048)
			(end -0.67945 -0.3048)
			(stroke
				(width 0.1)
				(type default)
			)
			(layer "B.Fab")
		)
		(fp_line
			(start -0.67945 -0.3048)
			(end -0.67945 0.3048)
			(stroke
				(width 0.1)
				(type default)
			)
			(layer "B.Fab")
		)
		(fp_line
			(start 0.12065 -0.2794)
			(end -0.12065 -0.2794)
			(stroke
				(width 0.1)
				(type default)
			)
			(layer "B.Fab")
		)
		(fp_line
			(start -0.12065 -0.2794)
			(end -0.12065 -0.3048)
			(stroke
				(width 0.1)
				(type default)
			)
			(layer "B.Fab")
		)
		(fp_line
			(start 0.12065 0.2794)
			(end 0.12065 0.3048)
			(stroke
				(width 0.1)
				(type default)
			)
			(layer "B.Fab")
		)
		(fp_line
			(start -0.120396 0.2794)
			(end 0.12065 0.2794)
			(stroke
				(width 0.1)
				(type default)
			)
			(layer "B.Fab")
		)
		(fp_line
			(start 0.67945 0.3048)
			(end 0.67945 -0.305054)
			(stroke
				(width 0.1)
				(type default)
			)
			(layer "B.Fab")
		)
		(fp_line
			(start 0.12065 0.3048)
			(end 0.67945 0.3048)
			(stroke
				(width 0.1)
				(type default)
			)
			(layer "B.Fab")
		)
		(fp_line
			(start -0.120396 0.3048)
			(end -0.120396 0.2794)
			(stroke
				(width 0.1)
				(type default)
			)
			(layer "B.Fab")
		)
		(fp_line
			(start -0.67945 0.3048)
			(end -0.120396 0.3048)
			(stroke
				(width 0.1)
				(type default)
			)
			(layer "B.Fab")
		)
		(pad "1" smd circle
			(at 0.40005 0 270)
			(size 0 0)
			(layers "B.Cu" "B.Mask" "B.Paste")
			(net "FM_FAN_PWR_EN_R")
		)
		(pad "2" smd circle
			(at -0.40005 0 270)
			(size 0 0)
			(layers "B.Cu" "B.Mask" "B.Paste")
			(net "FM_FAN_PWR_EN")
		)
	)
	(footprint ""
		(layer "B.Cu")
		(at 346.754958 -269.30731 180)
		(property "Reference" "C2256"
			(at 0 0 0)
			(layer "B.SilkS")
			(hide yes)
			(effects
				(font
					(size 1.27 1.27)
				)
				(justify mirror)
			)
		)
		(property "Value" ""
			(at 0 0 0)
			(layer "B.Fab")
			(effects
				(font
					(size 1.27 1.27)
				)
				(justify mirror)
			)
		)
		(duplicate_pad_numbers_are_jumpers no)
		(fp_line
			(start 0.7874 0.4064)
			(end 0.7874 -0.4064)
			(stroke
				(width 0.1524)
				(type default)
			)
			(layer "B.SilkS")
		)
		(fp_line
			(start 0.7874 -0.4064)
			(end -0.7874 -0.4064)
			(stroke
				(width 0.1524)
				(type default)
			)
			(layer "B.SilkS")
		)
		(fp_line
			(start -0.7874 0.4064)
			(end 0.7874 0.4064)
			(stroke
				(width 0.1524)
				(type default)
			)
			(layer "B.SilkS")
		)
		(fp_line
			(start -0.7874 -0.4064)
			(end -0.7874 0.4064)
			(stroke
				(width 0.1524)
				(type default)
			)
			(layer "B.SilkS")
		)
		(fp_line
			(start 0.67945 0.3048)
			(end 0.67945 -0.305054)
			(stroke
				(width 0.1)
				(type default)
			)
			(layer "B.Fab")
		)
		(fp_line
			(start 0.67945 -0.305054)
			(end 0.12065 -0.305054)
			(stroke
				(width 0.1)
				(type default)
			)
			(layer "B.Fab")
		)
		(fp_line
			(start 0.12065 0.3048)
			(end 0.67945 0.3048)
			(stroke
				(width 0.1)
				(type default)
			)
			(layer "B.Fab")
		)
		(fp_line
			(start 0.12065 0.2794)
			(end 0.12065 0.3048)
			(stroke
				(width 0.1)
				(type default)
			)
			(layer "B.Fab")
		)
		(fp_line
			(start 0.12065 -0.2794)
			(end -0.12065 -0.2794)
			(stroke
				(width 0.1)
				(type default)
			)
			(layer "B.Fab")
		)
		(fp_line
			(start 0.12065 -0.305054)
			(end 0.12065 -0.2794)
			(stroke
				(width 0.1)
				(type default)
			)
			(layer "B.Fab")
		)
		(fp_line
			(start -0.120396 0.3048)
			(end -0.120396 0.2794)
			(stroke
				(width 0.1)
				(type default)
			)
			(layer "B.Fab")
		)
		(fp_line
			(start -0.120396 0.2794)
			(end 0.12065 0.2794)
			(stroke
				(width 0.1)
				(type default)
			)
			(layer "B.Fab")
		)
		(fp_line
			(start -0.12065 -0.2794)
			(end -0.12065 -0.3048)
			(stroke
				(width 0.1)
				(type default)
			)
			(layer "B.Fab")
		)
		(fp_line
			(start -0.12065 -0.3048)
			(end -0.67945 -0.3048)
			(stroke
				(width 0.1)
				(type default)
			)
			(layer "B.Fab")
		)
		(fp_line
			(start -0.67945 0.3048)
			(end -0.120396 0.3048)
			(stroke
				(width 0.1)
				(type default)
			)
			(layer "B.Fab")
		)
		(fp_line
			(start -0.67945 -0.3048)
			(end -0.67945 0.3048)
			(stroke
				(width 0.1)
				(type default)
			)
			(layer "B.Fab")
		)
		(pad "1" smd circle
			(at 0.40005 0)
			(size 0 0)
			(layers "B.Cu" "B.Mask" "B.Paste")
			(net "PVDDCR_CPU1_P0")
		)
		(pad "2" smd circle
			(at -0.40005 0)
			(size 0 0)
			(layers "B.Cu" "B.Mask" "B.Paste")
			(net "GND")
		)
	)
)
